(kicad_pcb
	(version 20260206)
	(generator "pcbnew")
	(generator_version "10.0")
	(general
		(thickness 1.6)
		(legacy_teardrops no)
	)
	(paper "A4")
	(title_block
		(title "04192023_DAF0TMB3IC0_F0TG_MB_C_brd_V02_OCP.brd")
		(comment 1 "Grand Teton / footprints 6764-6769 of 8354")
	)
	(layers
		(0 "F.Cu" signal "TOP")
		(4 "In1.Cu" signal "GND")
		(6 "In2.Cu" signal "IN1")
		(8 "In3.Cu" signal "GND1")
		(10 "In4.Cu" signal "IN2")
		(12 "In5.Cu" signal "GND2")
		(14 "In6.Cu" signal "IN3")
		(16 "In7.Cu" signal "GND3")
		(18 "In8.Cu" signal "VCC")
		(20 "In9.Cu" signal "VCC1")
		(22 "In10.Cu" signal "GND4")
		(24 "In11.Cu" signal "IN4")
		(26 "In12.Cu" signal "GND5")
		(28 "In13.Cu" signal "IN5")
		(30 "In14.Cu" signal "GND6")
		(32 "In15.Cu" signal "IN6")
		(34 "In16.Cu" signal "GND7")
		(2 "B.Cu" signal "BOTTOM")
		(9 "F.Adhes" user "F.Adhesive")
		(11 "B.Adhes" user "B.Adhesive")
		(13 "F.Paste" user "Package Geometry/Pastemask Top")
		(15 "B.Paste" user "Package Geometry/Pastemask Bottom")
		(5 "F.SilkS" user "Ref Des/Silkscreen Top")
		(7 "B.SilkS" user "Ref Des/Silkscreen Bottom")
		(1 "F.Mask" user "Board Geometry/Soldermask Top")
		(3 "B.Mask" user "Board Geometry/Soldermask Bottom")
		(17 "Dwgs.User" user "User.Drawings")
		(19 "Cmts.User" user "User.Comments")
		(21 "Eco1.User" user "User.Eco1")
		(23 "Eco2.User" user "User.Eco2")
		(25 "Edge.Cuts" user "Board Geometry/Outline")
		(27 "Margin" user)
		(31 "F.CrtYd" user "Package Geometry/Place Bound Top")
		(29 "B.CrtYd" user "Package Geometry/Place Bound Bottom")
		(35 "F.Fab" user "Ref Des/Assembly Top")
		(33 "B.Fab" user "Ref Des/Assembly Bottom")
	)
	(footprint ""
		(layer "B.Cu")
		(at 208.748376 -120.944386 180)
		(property "Reference" "R757"
			(at 0 0 0)
			(layer "B.SilkS")
			(hide yes)
			(effects
				(font
					(size 1.27 1.27)
				)
				(justify mirror)
			)
		)
		(property "Value" ""
			(at 0 0 0)
			(layer "B.Fab")
			(effects
				(font
					(size 1.27 1.27)
				)
				(justify mirror)
			)
		)
		(duplicate_pad_numbers_are_jumpers no)
		(fp_line
			(start 0.7874 0.4064)
			(end 0.7874 -0.4064)
			(stroke
				(width 0.1524)
				(type default)
			)
			(layer "B.SilkS")
		)
		(fp_line
			(start 0.7874 -0.4064)
			(end -0.7874 -0.4064)
			(stroke
				(width 0.1524)
				(type default)
			)
			(layer "B.SilkS")
		)
		(fp_line
			(start -0.7874 0.4064)
			(end 0.7874 0.4064)
			(stroke
				(width 0.1524)
				(type default)
			)
			(layer "B.SilkS")
		)
		(fp_line
			(start -0.7874 -0.4064)
			(end -0.7874 0.4064)
			(stroke
				(width 0.1524)
				(type default)
			)
			(layer "B.SilkS")
		)
		(fp_line
			(start 0.67945 0.3048)
			(end 0.67945 -0.305054)
			(stroke
				(width 0.1)
				(type default)
			)
			(layer "B.Fab")
		)
		(fp_line
			(start 0.67945 -0.305054)
			(end 0.12065 -0.305054)
			(stroke
				(width 0.1)
				(type default)
			)
			(layer "B.Fab")
		)
		(fp_line
			(start 0.12065 0.3048)
			(end 0.67945 0.3048)
			(stroke
				(width 0.1)
				(type default)
			)
			(layer "B.Fab")
		)
		(fp_line
			(start 0.12065 0.2794)
			(end 0.12065 0.3048)
			(stroke
				(width 0.1)
				(type default)
			)
			(layer "B.Fab")
		)
		(fp_line
			(start 0.12065 -0.2794)
			(end -0.12065 -0.2794)
			(stroke
				(width 0.1)
				(type default)
			)
			(layer "B.Fab")
		)
		(fp_line
			(start 0.12065 -0.305054)
			(end 0.12065 -0.2794)
			(stroke
				(width 0.1)
				(type default)
			)
			(layer "B.Fab")
		)
		(fp_line
			(start -0.120396 0.3048)
			(end -0.120396 0.2794)
			(stroke
				(width 0.1)
				(type default)
			)
			(layer "B.Fab")
		)
		(fp_line
			(start -0.120396 0.2794)
			(end 0.12065 0.2794)
			(stroke
				(width 0.1)
				(type default)
			)
			(layer "B.Fab")
		)
		(fp_line
			(start -0.12065 -0.2794)
			(end -0.12065 -0.3048)
			(stroke
				(width 0.1)
				(type default)
			)
			(layer "B.Fab")
		)
		(fp_line
			(start -0.12065 -0.3048)
			(end -0.67945 -0.3048)
			(stroke
				(width 0.1)
				(type default)
			)
			(layer "B.Fab")
		)
		(fp_line
			(start -0.67945 0.3048)
			(end -0.120396 0.3048)
			(stroke
				(width 0.1)
				(type default)
			)
			(layer "B.Fab")
		)
		(fp_line
			(start -0.67945 -0.3048)
			(end -0.67945 0.3048)
			(stroke
				(width 0.1)
				(type default)
			)
			(layer "B.Fab")
		)
		(pad "1" smd circle
			(at 0.40005 0)
			(size 0 0)
			(layers "B.Cu" "B.Mask" "B.Paste")
			(net "E1S_0_P3V3_EN")
		)
		(pad "2" smd circle
			(at -0.40005 0)
			(size 0 0)
			(layers "B.Cu" "B.Mask" "B.Paste")
			(net "P3V3_AUX")
		)
	)
	(footprint ""
		(layer "B.Cu")
		(at 108.501434 -246.402352)
		(property "Reference" "C2304"
			(at 0 0 0)
			(layer "B.SilkS")
			(hide yes)
			(effects
				(font
					(size 1.27 1.27)
				)
				(justify mirror)
			)
		)
		(property "Value" ""
			(at 0 0 0)
			(layer "B.Fab")
			(effects
				(font
					(size 1.27 1.27)
				)
				(justify mirror)
			)
		)
		(duplicate_pad_numbers_are_jumpers no)
		(fp_line
			(start -0.7874 -0.4064)
			(end -0.7874 0.4064)
			(stroke
				(width 0.1524)
				(type default)
			)
			(layer "B.SilkS")
		)
		(fp_line
			(start -0.7874 0.4064)
			(end 0.7874 0.4064)
			(stroke
				(width 0.1524)
				(type default)
			)
			(layer "B.SilkS")
		)
		(fp_line
			(start 0.7874 -0.4064)
			(end -0.7874 -0.4064)
			(stroke
				(width 0.1524)
				(type default)
			)
			(layer "B.SilkS")
		)
		(fp_line
			(start 0.7874 0.4064)
			(end 0.7874 -0.4064)
			(stroke
				(width 0.1524)
				(type default)
			)
			(layer "B.SilkS")
		)
		(fp_line
			(start -0.67945 -0.3048)
			(end -0.67945 0.3048)
			(stroke
				(width 0.1)
				(type default)
			)
			(layer "B.Fab")
		)
		(fp_line
			(start -0.67945 0.3048)
			(end -0.120396 0.3048)
			(stroke
				(width 0.1)
				(type default)
			)
			(layer "B.Fab")
		)
		(fp_line
			(start -0.12065 -0.3048)
			(end -0.67945 -0.3048)
			(stroke
				(width 0.1)
				(type default)
			)
			(layer "B.Fab")
		)
		(fp_line
			(start -0.12065 -0.2794)
			(end -0.12065 -0.3048)
			(stroke
				(width 0.1)
				(type default)
			)
			(layer "B.Fab")
		)
		(fp_line
			(start -0.120396 0.2794)
			(end 0.12065 0.2794)
			(stroke
				(width 0.1)
				(type default)
			)
			(layer "B.Fab")
		)
		(fp_line
			(start -0.120396 0.3048)
			(end -0.120396 0.2794)
			(stroke
				(width 0.1)
				(type default)
			)
			(layer "B.Fab")
		)
		(fp_line
			(start 0.12065 -0.305054)
			(end 0.12065 -0.2794)
			(stroke
				(width 0.1)
				(type default)
			)
			(layer "B.Fab")
		)
		(fp_line
			(start 0.12065 -0.2794)
			(end -0.12065 -0.2794)
			(stroke
				(width 0.1)
				(type default)
			)
			(layer "B.Fab")
		)
		(fp_line
			(start 0.12065 0.2794)
			(end 0.12065 0.3048)
			(stroke
				(width 0.1)
				(type default)
			)
			(layer "B.Fab")
		)
		(fp_line
			(start 0.12065 0.3048)
			(end 0.67945 0.3048)
			(stroke
				(width 0.1)
				(type default)
			)
			(layer "B.Fab")
		)
		(fp_line
			(start 0.67945 -0.305054)
			(end 0.12065 -0.305054)
			(stroke
				(width 0.1)
				(type default)
			)
			(layer "B.Fab")
		)
		(fp_line
			(start 0.67945 0.3048)
			(end 0.67945 -0.305054)
			(stroke
				(width 0.1)
				(type default)
			)
			(layer "B.Fab")
		)
		(pad "1" smd circle
			(at 0.40005 0 180)
			(size 0 0)
			(layers "B.Cu" "B.Mask" "B.Paste")
			(net "PVDDCR_CPU0_P1")
		)
		(pad "2" smd circle
			(at -0.40005 0 180)
			(size 0 0)
			(layers "B.Cu" "B.Mask" "B.Paste")
			(net "GND")
		)
	)
	(footprint ""
		(layer "B.Cu")
		(at 188.712094 -115.022376)
		(property "Reference" "C361"
			(at 0 0 0)
			(layer "B.SilkS")
			(hide yes)
			(effects
				(font
					(size 1.27 1.27)
				)
				(justify mirror)
			)
		)
		(property "Value" ""
			(at 0 0 0)
			(layer "B.Fab")
			(effects
				(font
					(size 1.27 1.27)
				)
				(justify mirror)
			)
		)
		(duplicate_pad_numbers_are_jumpers no)
		(fp_line
			(start -0.69215 -0.2921)
			(end -0.69215 0.2921)
			(stroke
				(width 0.1524)
				(type default)
			)
			(layer "B.SilkS")
		)
		(fp_line
			(start -0.69215 0.2921)
			(end 0.69215 0.2921)
			(stroke
				(width 0.1524)
				(type default)
			)
			(layer "B.SilkS")
		)
		(fp_line
			(start 0.69215 -0.2921)
			(end -0.69215 -0.2921)
			(stroke
				(width 0.1524)
				(type default)
			)
			(layer "B.SilkS")
		)
		(fp_line
			(start 0.69215 0.2921)
			(end 0.69215 -0.2921)
			(stroke
				(width 0.1524)
				(type default)
			)
			(layer "B.SilkS")
		)
		(fp_line
			(start -0.51435 -0.2794)
			(end -0.51435 0.2794)
			(stroke
				(width 0.1)
				(type default)
			)
			(layer "B.Fab")
		)
		(fp_line
			(start -0.51435 0.2794)
			(end 0.51435 0.2794)
			(stroke
				(width 0.1)
				(type default)
			)
			(layer "B.Fab")
		)
		(fp_line
			(start 0.51435 -0.2794)
			(end -0.51435 -0.2794)
			(stroke
				(width 0.1)
				(type default)
			)
			(layer "B.Fab")
		)
		(fp_line
			(start 0.51435 0.2794)
			(end 0.51435 -0.2794)
			(stroke
				(width 0.1)
				(type default)
			)
			(layer "B.Fab")
		)
		(pad "1" smd circle
			(at 0.40005 0 180)
			(size 0 0)
			(layers "B.Cu" "B.Mask" "B.Paste")
			(net "P3V3_AUX")
		)
		(pad "2" smd circle
			(at -0.40005 0 180)
			(size 0 0)
			(layers "B.Cu" "B.Mask" "B.Paste")
			(net "GND")
		)
		(zone
			(layer "B.Cu")
			(hatch none 0.5)
			(connect_pads
				(clearance 0)
			)
			(min_thickness 0.25)
			(keepout
				(tracks not_allowed)
				(vias allowed)
				(pads allowed)
				(copperpour not_allowed)
				(footprints allowed)
			)
			(placement
				(enabled no)
				(sheetname "")
			)
			(fill
				(thermal_gap 0.5)
				(thermal_bridge_width 0.5)
				(island_removal_mode 0)
			)
			(polygon
				(pts
					(xy 188.521594 -114.934746) (xy 188.521594 -115.110006) (xy 188.611764 -115.168426) (xy 188.811154 -115.168426)
					(xy 188.902594 -115.11026) (xy 188.902594 -114.934746) (xy 188.811154 -114.87658) (xy 188.611764 -114.87658)
				)
			)
		)
	)
	(footprint ""
		(layer "B.Cu")
		(at 403.377146 -354.439728 -90)
		(property "Reference" "R6126"
			(at 0 0 90)
			(layer "B.SilkS")
			(hide yes)
			(effects
				(font
					(size 1.27 1.27)
				)
				(justify mirror)
			)
		)
		(property "Value" ""
			(at 0 0 90)
			(layer "B.Fab")
			(effects
				(font
					(size 1.27 1.27)
				)
				(justify mirror)
			)
		)
		(duplicate_pad_numbers_are_jumpers no)
		(fp_line
			(start -0.7874 0.4064)
			(end 0.7874 0.4064)
			(stroke
				(width 0.1524)
				(type default)
			)
			(layer "B.SilkS")
		)
		(fp_line
			(start 0.7874 0.4064)
			(end 0.7874 -0.4064)
			(stroke
				(width 0.1524)
				(type default)
			)
			(layer "B.SilkS")
		)
		(fp_line
			(start -0.7874 -0.4064)
			(end -0.7874 0.4064)
			(stroke
				(width 0.1524)
				(type default)
			)
			(layer "B.SilkS")
		)
		(fp_line
			(start 0.7874 -0.4064)
			(end -0.7874 -0.4064)
			(stroke
				(width 0.1524)
				(type default)
			)
			(layer "B.SilkS")
		)
		(fp_line
			(start -0.67945 0.3048)
			(end -0.120396 0.3048)
			(stroke
				(width 0.1)
				(type default)
			)
			(layer "B.Fab")
		)
		(fp_line
			(start -0.120396 0.3048)
			(end -0.120396 0.2794)
			(stroke
				(width 0.1)
				(type default)
			)
			(layer "B.Fab")
		)
		(fp_line
			(start 0.12065 0.3048)
			(end 0.67945 0.3048)
			(stroke
				(width 0.1)
				(type default)
			)
			(layer "B.Fab")
		)
		(fp_line
			(start 0.67945 0.3048)
			(end 0.67945 -0.305054)
			(stroke
				(width 0.1)
				(type default)
			)
			(layer "B.Fab")
		)
		(fp_line
			(start -0.120396 0.2794)
			(end 0.12065 0.2794)
			(stroke
				(width 0.1)
				(type default)
			)
			(layer "B.Fab")
		)
		(fp_line
			(start 0.12065 0.2794)
			(end 0.12065 0.3048)
			(stroke
				(width 0.1)
				(type default)
			)
			(layer "B.Fab")
		)
		(fp_line
			(start -0.12065 -0.2794)
			(end -0.12065 -0.3048)
			(stroke
				(width 0.1)
				(type default)
			)
			(layer "B.Fab")
		)
		(fp_line
			(start 0.12065 -0.2794)
			(end -0.12065 -0.2794)
			(stroke
				(width 0.1)
				(type default)
			)
			(layer "B.Fab")
		)
		(fp_line
			(start -0.67945 -0.3048)
			(end -0.67945 0.3048)
			(stroke
				(width 0.1)
				(type default)
			)
			(layer "B.Fab")
		)
		(fp_line
			(start -0.12065 -0.3048)
			(end -0.67945 -0.3048)
			(stroke
				(width 0.1)
				(type default)
			)
			(layer "B.Fab")
		)
		(fp_line
			(start 0.12065 -0.305054)
			(end 0.12065 -0.2794)
			(stroke
				(width 0.1)
				(type default)
			)
			(layer "B.Fab")
		)
		(fp_line
			(start 0.67945 -0.305054)
			(end 0.12065 -0.305054)
			(stroke
				(width 0.1)
				(type default)
			)
			(layer "B.Fab")
		)
		(pad "1" smd circle
			(at 0.40005 0 90)
			(size 0 0)
			(layers "B.Cu" "B.Mask" "B.Paste")
			(net "FM_BOARD_SKU_ID3")
		)
		(pad "2" smd circle
			(at -0.40005 0 90)
			(size 0 0)
			(layers "B.Cu" "B.Mask" "B.Paste")
			(net "GND")
		)
	)
	(footprint ""
		(layer "B.Cu")
		(at 300.82109 -244.08511 180)
		(property "Reference" "R376"
			(at 0 0 0)
			(layer "B.SilkS")
			(hide yes)
			(effects
				(font
					(size 1.27 1.27)
				)
				(justify mirror)
			)
		)
		(property "Value" ""
			(at 0 0 0)
			(layer "B.Fab")
			(effects
				(font
					(size 1.27 1.27)
				)
				(justify mirror)
			)
		)
		(duplicate_pad_numbers_are_jumpers no)
		(fp_line
			(start 0.7874 0.4064)
			(end 0.7874 -0.4064)
			(stroke
				(width 0.1524)
				(type default)
			)
			(layer "B.SilkS")
		)
		(fp_line
			(start 0.7874 -0.4064)
			(end -0.7874 -0.4064)
			(stroke
				(width 0.1524)
				(type default)
			)
			(layer "B.SilkS")
		)
		(fp_line
			(start -0.7874 0.4064)
			(end 0.7874 0.4064)
			(stroke
				(width 0.1524)
				(type default)
			)
			(layer "B.SilkS")
		)
		(fp_line
			(start -0.7874 -0.4064)
			(end -0.7874 0.4064)
			(stroke
				(width 0.1524)
				(type default)
			)
			(layer "B.SilkS")
		)
		(fp_line
			(start 0.67945 0.3048)
			(end 0.67945 -0.305054)
			(stroke
				(width 0.1)
				(type default)
			)
			(layer "B.Fab")
		)
		(fp_line
			(start 0.67945 -0.305054)
			(end 0.12065 -0.305054)
			(stroke
				(width 0.1)
				(type default)
			)
			(layer "B.Fab")
		)
		(fp_line
			(start 0.12065 0.3048)
			(end 0.67945 0.3048)
			(stroke
				(width 0.1)
				(type default)
			)
			(layer "B.Fab")
		)
		(fp_line
			(start 0.12065 0.2794)
			(end 0.12065 0.3048)
			(stroke
				(width 0.1)
				(type default)
			)
			(layer "B.Fab")
		)
		(fp_line
			(start 0.12065 -0.2794)
			(end -0.12065 -0.2794)
			(stroke
				(width 0.1)
				(type default)
			)
			(layer "B.Fab")
		)
		(fp_line
			(start 0.12065 -0.305054)
			(end 0.12065 -0.2794)
			(stroke
				(width 0.1)
				(type default)
			)
			(layer "B.Fab")
		)
		(fp_line
			(start -0.120396 0.3048)
			(end -0.120396 0.2794)
			(stroke
				(width 0.1)
				(type default)
			)
			(layer "B.Fab")
		)
		(fp_line
			(start -0.120396 0.2794)
			(end 0.12065 0.2794)
			(stroke
				(width 0.1)
				(type default)
			)
			(layer "B.Fab")
		)
		(fp_line
			(start -0.12065 -0.2794)
			(end -0.12065 -0.3048)
			(stroke
				(width 0.1)
				(type default)
			)
			(layer "B.Fab")
		)
		(fp_line
			(start -0.12065 -0.3048)
			(end -0.67945 -0.3048)
			(stroke
				(width 0.1)
				(type default)
			)
			(layer "B.Fab")
		)
		(fp_line
			(start -0.67945 0.3048)
			(end -0.120396 0.3048)
			(stroke
				(width 0.1)
				(type default)
			)
			(layer "B.Fab")
		)
		(fp_line
			(start -0.67945 -0.3048)
			(end -0.67945 0.3048)
			(stroke
				(width 0.1)
				(type default)
			)
			(layer "B.Fab")
		)
		(pad "1" smd circle
			(at 0.40005 0)
			(size 0 0)
			(layers "B.Cu" "B.Mask" "B.Paste")
			(net "M_B_CPU0_ALERT_N")
		)
		(pad "2" smd circle
			(at -0.40005 0)
			(size 0 0)
			(layers "B.Cu" "B.Mask" "B.Paste")
			(net "M_B_CPU0_ALERT_R_N")
		)
	)
	(footprint ""
		(layer "B.Cu")
		(at 361.595924 -395.127988 -90)
		(property "Reference" "C596"
			(at 0 0 90)
			(layer "B.SilkS")
			(hide yes)
			(effects
				(font
					(size 1.27 1.27)
				)
				(justify mirror)
			)
		)
		(property "Value" ""
			(at 0 0 90)
			(layer "B.Fab")
			(effects
				(font
					(size 1.27 1.27)
				)
				(justify mirror)
			)
		)
		(duplicate_pad_numbers_are_jumpers no)
		(fp_line
			(start -0.7874 0.4064)
			(end 0.7874 0.4064)
			(stroke
				(width 0.1524)
				(type default)
			)
			(layer "B.SilkS")
		)
		(fp_line
			(start 0.7874 0.4064)
			(end 0.7874 -0.4064)
			(stroke
				(width 0.1524)
				(type default)
			)
			(layer "B.SilkS")
		)
		(fp_line
			(start -0.7874 -0.4064)
			(end -0.7874 0.4064)
			(stroke
				(width 0.1524)
				(type default)
			)
			(layer "B.SilkS")
		)
		(fp_line
			(start 0.7874 -0.4064)
			(end -0.7874 -0.4064)
			(stroke
				(width 0.1524)
				(type default)
			)
			(layer "B.SilkS")
		)
		(fp_line
			(start -0.67945 0.3048)
			(end -0.120396 0.3048)
			(stroke
				(width 0.1)
				(type default)
			)
			(layer "B.Fab")
		)
		(fp_line
			(start -0.120396 0.3048)
			(end -0.120396 0.2794)
			(stroke
				(width 0.1)
				(type default)
			)
			(layer "B.Fab")
		)
		(fp_line
			(start 0.12065 0.3048)
			(end 0.67945 0.3048)
			(stroke
				(width 0.1)
				(type default)
			)
			(layer "B.Fab")
		)
		(fp_line
			(start 0.67945 0.3048)
			(end 0.67945 -0.305054)
			(stroke
				(width 0.1)
				(type default)
			)
			(layer "B.Fab")
		)
		(fp_line
			(start -0.120396 0.2794)
			(end 0.12065 0.2794)
			(stroke
				(width 0.1)
				(type default)
			)
			(layer "B.Fab")
		)
		(fp_line
			(start 0.12065 0.2794)
			(end 0.12065 0.3048)
			(stroke
				(width 0.1)
				(type default)
			)
			(layer "B.Fab")
		)
		(fp_line
			(start -0.12065 -0.2794)
			(end -0.12065 -0.3048)
			(stroke
				(width 0.1)
				(type default)
			)
			(layer "B.Fab")
		)
		(fp_line
			(start 0.12065 -0.2794)
			(end -0.12065 -0.2794)
			(stroke
				(width 0.1)
				(type default)
			)
			(layer "B.Fab")
		)
		(fp_line
			(start -0.67945 -0.3048)
			(end -0.67945 0.3048)
			(stroke
				(width 0.1)
				(type default)
			)
			(layer "B.Fab")
		)
		(fp_line
			(start -0.12065 -0.3048)
			(end -0.67945 -0.3048)
			(stroke
				(width 0.1)
				(type default)
			)
			(layer "B.Fab")
		)
		(fp_line
			(start 0.12065 -0.305054)
			(end 0.12065 -0.2794)
			(stroke
				(width 0.1)
				(type default)
			)
			(layer "B.Fab")
		)
		(fp_line
			(start 0.67945 -0.305054)
			(end 0.12065 -0.305054)
			(stroke
				(width 0.1)
				(type default)
			)
			(layer "B.Fab")
		)
		(pad "1" smd circle
			(at 0.40005 0 90)
			(size 0 0)
			(layers "B.Cu" "B.Mask" "B.Paste")
			(net "P1V8_CPU0_RT_1D")
		)
		(pad "2" smd circle
			(at -0.40005 0 90)
			(size 0 0)
			(layers "B.Cu" "B.Mask" "B.Paste")
			(net "GND")
		)
	)
)
